FILE_TYPE = CONNECTIVITY;
{Allegro Design Entry HDL 16.6-p007 (v16-6-112F) 10/10/2012}
"PAGE_NUMBER" = 155;
0"NC";
1"P3V3_STBY\g";
2"GND\g";
3"P5V_STBY\g";
4"P5V_STBY\g";
5"P12V_STBY\g";
6"P5V_STBY\g";
7"GND\g";
8"P3V3_STBY\g";
9"GND\g";
10"GND\g";
11"P5V\g";
12"UART_PWR_SEL";
13"FM_CPLD_DBG_PWR_EN";
14"P5V_STBY_DGB_FS"VOLTAGE"5";
15"LED_POSTCODE_7";
16"LED_POSTCODE_6";
17"LED_POSTCODE_5";
18"LED_POSTCODE_4";
19"LED_POSTCODE_2";
20"LED_POSTCODE_3";
21"LED_POSTCODE_1";
22"LED_POSTCODE_0";
23"LED_POSTCODE_7_R";
24"LED_POSTCODE_4_R";
25"LED_POSTCODE_5_R";
26"LED_POSTCODE_1_R";
27"LED_POSTCODE_2_R";
28"LED_POSTCODE_3_R";
29"LED_POSTCODE_0_R";
30"FM_CPLD_DBG_PWR_EN_N";
31"FM_CPLD_DBG_PWR_EN_R_N";
32"FM_DEBUG_RST_BTN_N";
33"SPA_MID_DBG_TX";
34"LED_POSTCODE_6_R";
35"LED_POSTCODE_4_R";
36"LED_POSTCODE_2_R";
37"LED_POSTCODE_0_R";
38"LED_POSTCODE_7_R";
39"LED_POSTCODE_5_R";
40"LED_POSTCODE_3_R";
41"LED_POSTCODE_1_R";
42"SPA_MID_DBG1__RX";
43"FM_UART_SWITCH_N";
44"SPA_5V_SIN_SW";
45"LED_POSTCODE_6_R";
46"SPA_SIN_SW_R";
47"P5V_STBY_DBG"VOLTAGE"5";
%"CAP_A"
"1","(-4100,1050)","0","dev_discrete","I127";
;
CDS_LIB"dev_discrete"
CDS_LOCATION"C9A1"
ROOM"BMC_DEBUG_HEADER"
$SEC"1"
CDS_SEC"1"
BOM_COST"DEBUG"
PART_NUMBER"A36096-030"
PACK_TYPE"0402V"
VOLTAGE"16V"
VALUE"0.1UF"
LOCATION"C9A1"
MATERIAL"X7R"
TOLERANCE"10%";
"B"
$PN"2"10;
"A"
$PN"1"14;
%"GND"
"1","(-4100,825)","0","mstr_symbols","I128";
;
VOLTAGE"0.0V"
CDS_LIB"mstr_symbols"
BODY_TYPE"PLUMBING"
SIZE"1B"
HDL_POWER"GND";
"A\NAC"10;
%"FUSE"
"1","(-4275,2625)","0","mstr_discrete","I129";
;
ROOM"BMC_DEBUG_HEADER"
CDS_LOCATION"F1L1"
SEC"1"
BOM_COST"DEBUG"
SEC_TYPE"SMT"
PACK_TYPE"SMT"
CDS_LIB"mstr_discrete"
MATERIAL"IC"
PART_NUMBER"H45581-001"
LOCATION"F1L1"
CDS_SEC"1";
"A<SIZE-1..0>"
$PN"1"47;
"B<SIZE-1..0>"
$PN"2"14;
%"RES"
"2","(-6050,2575)","0","mstr_discrete","I130";
;
BOM_COST"DEBUG"
SEC_TYPE"0402"
SEC"1"
ROOM"BMC_DEBUG_HEADER"
CDS_LOCATION"R1L9"
CDS_LIB"mstr_discrete"
LOCATION"R1L9"
MATERIAL"CHIP"
VALUE"100.0K"
WATTAGE"1/16W"
TOLERANCE"1%"
PACK_TYPE"0402"
PART_NUMBER"G21796-010"
CDS_SEC"1";
"A"
$PN"1"5;
"B"
$PN"2"13;
%"CONN14_H54902001"
"1","(-4450,1500)","0","mstr_conn","I171";
;
CDS_LMAN_SYM_OUTLINE"-250,250,250,-250"
CDS_LIB"mstr_conn"
ROOM"BMC_DEBUG_HEADER"
CDS_LOCATION"J9A2"
CDS_SEC"1"
PACK_TYPE"PIP"
$SEC"1"
BOM_COST"DEBUG"
PART_NUMBER"H54902-001"
MATERIAL"CONN"
LOCATION"J9A2";
"IO13"
$PN"13"2;
"IO11"
$PN"11"32;
"IO9"
$PN"9"33;
"IO7"
$PN"7"34;
"IO5"
$PN"5"35;
"IO3"
$PN"3"36;
"IO1"
$PN"1"37;
"IO2"
$PN"2"41;
"IO14"
$PN"14"14;
"IO12"
$PN"12"43;
"IO10"
$PN"10"44;
"IO8"
$PN"8"38;
"IO4"
$PN"4"40;
"IO6"
$PN"6"39;
%"TTL1G07_A"
"1","(-2550,1400)","0","mstr_ttl","I178";
;
PACK_TYPE"SOP"
BOM_COST"DEBUG"
SEC_TYPE"SOP"
SEC"1"
CDS_LOCATION"U9A1"
ROOM"BMC_DEBUG_HEADER"
CDS_LIB"mstr_ttl"
PART_NUMBER"C88419-001"
VALUE"74LVC1G07"
MATERIAL"IC"
LOCATION"U9A1"
POWER_GROUP"VCC=P3V3_STBY;GND=GND"
CDS_SEC"1";
"Y"
$PN"4"46;
"A"
$PN"2"44;
%"GND"
"1","(-6050,1600)","0","mstr_symbols","I180";
;
BODY_TYPE"PLUMBING"
VOLTAGE"0.0V"
SIZE"1B"
CDS_LIB"mstr_symbols"
HDL_POWER"GND";
"A\NAC"9;
%"P3V3_STBY"
"1","(-1550,3325)","0","mstr_symbols","I183";
;
HDL_POWER"P3V3_STBY"
VOLTAGE"3.3V"
BODY_TYPE"PLUMBING"
CDS_LIB"mstr_symbols"
SIZE"1B";
"G\NAC"8;
%"CAP_A"
"1","(-1550,3025)","0","dev_discrete","I184";
;
CDS_LIB"dev_discrete"
CDS_LOCATION"C1T56"
SEC"1"
CDS_SEC"1"
ROOM"BMC_DEBUG_HEADER"
SEC_TYPE"0402V"
BOM_COST"DEBUG"
VOLTAGE"16V"
TOLERANCE"10%"
MATERIAL"X7R"
PACK_TYPE"0402V"
VALUE"0.1UF"
LOCATION"C1T56"
PART_NUMBER"A36096-030";
"B"
$PN"2"7;
"A"
$PN"1"8;
%"GND"
"1","(-1550,2725)","0","mstr_symbols","I185";
;
VOLTAGE"0.0V"
CDS_LIB"mstr_symbols"
BODY_TYPE"PLUMBING"
HDL_POWER"GND"
SIZE"1B";
"A\NAC"7;
%"RES"
"1","(-7050,2000)","0","mstr_discrete","I186";
;
$SEC"1"
CDS_LOCATION"R1L2"
ROOM"BMC_DEBUG_HEADER"
CDS_SEC"1"
BOM_COST"DEBUG"
CDS_LIB"mstr_discrete"
MATERIAL"CHIP"
PART_NUMBER"G21796-066"
WATTAGE"1/16W"
PACK_TYPE"0402"
TOLERANCE"1%"
LOCATION"R1L2"
VALUE"10.0";
"B"
$PN"2"31;
"A"
$PN"1"30;
%"FET_N_DUAL"
"5","(-6050,2100)","0","mstr_discrete","I187";
;
PACK_TYPE"SMLF"
CDS_LIB"mstr_discrete"
ROOM"BMC"
CDS_LOCATION"Q1L2"
SEC"2"
BOM_COST"BMC_DEBUG_HEADER"
SEC_TYPE"SMLF"
PART_NUMBER"E40049-001"
MATERIAL"FET"
LOCATION"Q1L2"
VALUE"NTJD4001N"
CDS_SEC"2";
"GATE <SIZE -1..0>"
$PN"5"31;
"SOURCE <SIZE-1..0>"
$PN"4"9;
"DRAIN <SIZE -1..0>"
$PN"3"13;
%"FET_N_DUAL"
"5","(-4950,2625)","1","mstr_discrete","I188";
;
CDS_LOCATION"Q1L2"
SEC"1"
SEC_TYPE"SMLF"
CDS_LIB"mstr_discrete"
PACK_TYPE"SMLF"
ROOM"BMC"
BOM_COST"BMC_DEBUG_HEADER"
LOCATION"Q1L2"
PART_NUMBER"E40049-001"
VALUE"NTJD4001N"
MATERIAL"FET"
CDS_SEC"1";
"GATE <SIZE -1..0>"
$PN"2"13;
"SOURCE <SIZE-1..0>"
$PN"1"47;
"DRAIN <SIZE -1..0>"
$PN"6"12;
%"RES"
"2","(-2950,1725)","0","mstr_discrete","I191";
;
CDS_LIB"mstr_discrete"
CDS_LOCATION"R9A6"
ROOM"BMC"
$SEC"1"
CDS_SEC"1"
BOM_COST"BMC_DEBUG_HEADER"
MATERIAL"EMPTY"
WATTAGE"1/16W"
VALUE"20.0K"
LOCATION"R9A6"
TOLERANCE"1%"
PACK_TYPE"0402"
PART_NUMBER"G21796-040";
"A"
$PN"1"6;
"B"
$PN"2"44;
%"P5V_STBY"
"1","(-2950,1975)","0","mstr_symbols","I192";
;
HDL_POWER"P5V_STBY"
BODY_TYPE"PLUMBING"
CDS_LIB"mstr_symbols"
SIZE"1B"
VOLTAGE"5.0V";
"G\NAC"6;
%"P12V_STBY"
"1","(-6050,2900)","0","mstr_symbols","I193";
;
CDS_LIB"mstr_symbols"
HDL_POWER"P12V_STBY"
BODY_TYPE"PLUMBING"
SIZE"1B"
VOLTAGE"12.0V";
"G\NAC"5;
%"P5V_STBY"
"1","(-3325,1975)","0","mstr_symbols","I194";
;
HDL_POWER"P5V_STBY"
BODY_TYPE"PLUMBING"
SIZE"1B"
CDS_LIB"mstr_symbols"
VOLTAGE"5.0V";
"G\NAC"4;
%"RES"
"2","(-3325,1725)","2","mstr_discrete","I195";
;
ROOM"IO_SLOT"
BOM_COST"IO_SLOT"
CDS_LIB"mstr_discrete"
PART_NUMBER"G21796-107"
MATERIAL"CHIP"
WATTAGE"1/16W"
PACK_TYPE"0402"
TOLERANCE"1%"
VALUE"15.0K"
LOCATION"R9A5"
CDS_LOCATION"R9A5"
$SEC"1"
CDS_SEC"1";
"A"
$PN"1"4;
"B"
$PN"2"43;
%"RES"
"1","(-2400,1775)","0","mstr_discrete","I196";
;
BOM_COST"DEBUG"
ROOM"BMC_DEBUG_HEADER"
CDS_LIB"mstr_discrete"
MATERIAL"CHIP"
TOLERANCE"5%"
LOCATION"R6W19"
STATUS"NOPOP"
PART_NUMBER"G21497-005"
VALUE"0.0"
WATTAGE"1/16W"
PACK_TYPE"0402"
CDS_LOCATION"R6W19"
$SEC"1"
CDS_SEC"1";
"B"
$PN"2"46;
"A"
$PN"1"44;
%"CONN3_C95678002"
"1","(-5250,3050)","2","mstr_conn","I198";
;
CDS_LIB"mstr_conn"
ROOM"SMBUS"
PACK_TYPE"PIP"
BOM_COST"SM_CONTROLLER"
LOCATION"J1W1"
MATERIAL"CONN"
PART_NUMBER"C95678-002";
"IO1 \B"11;
"IO2 \B"12;
"IO3 \B"3;
%"P5V_STBY"
"1","(-4950,2950)","0","mstr_symbols","I199";
;
CDS_LIB"mstr_symbols"
SIZE"1B"
VOLTAGE"5.0V"
BODY_TYPE"PLUMBING"
HDL_POWER"P5V_STBY";
"G\NAC"3;
%"P5V"
"1","(-5500,3300)","0","mstr_symbols","I200";
;
CDS_LIB"mstr_symbols"
HDL_POWER"P5V"
BODY_TYPE"PLUMBING"
SIZE"1B"
VOLTAGE"5.0V";
"G\NAC"11;
%"GND"
"1","(-4825,1125)","0","mstr_symbols","I41";
;
VOLTAGE"0.0V"
CDS_LIB"mstr_symbols"
BODY_TYPE"PLUMBING"
HDL_POWER"GND"
SIZE"1B";
"A\NAC"2;
%"RES"
"1","(-1575,1400)","0","mstr_discrete","I53";
;
BOM_COST"DEBUG"
SEC_TYPE"0402"
SEC"1"
ROOM"BMC_DEBUG_HEADER"
CDS_LIB"mstr_discrete"
CDS_LOCATION"R9A8"
PACK_TYPE"0402"
MATERIAL"CHIP"
VALUE"0.0"
WATTAGE"1/16W"
PART_NUMBER"G21497-005"
LOCATION"R9A8"
TOLERANCE"5%"
CDS_SEC"1";
"B"
$PN"2"42;
"A"
$PN"1"46;
%"RES"
"1","(-6900,4650)","0","mstr_discrete","I65";
;
PART_NUMBER"G21796-066"
PACK_TYPE"0402"
TOLERANCE"1%"
LOCATION"R1L32"
VALUE"10.0"
WATTAGE"1/16W"
CDS_LIB"mstr_discrete"
MATERIAL"CHIP"
ROOM"BMC_DEBUG_HEADER"
CDS_LOCATION"R1L32"
$SEC"1"
CDS_SEC"1"
BOM_COST"DEBUG";
"B"
$PN"2"29;
"A"
$PN"1"22;
%"RES"
"1","(-6900,4500)","0","mstr_discrete","I66";
;
PART_NUMBER"G21796-066"
PACK_TYPE"0402"
TOLERANCE"1%"
LOCATION"R1L30"
VALUE"10.0"
WATTAGE"1/16W"
CDS_LIB"mstr_discrete"
MATERIAL"CHIP"
$SEC"1"
CDS_SEC"1"
BOM_COST"DEBUG"
ROOM"BMC_DEBUG_HEADER"
CDS_LOCATION"R1L30";
"B"
$PN"2"26;
"A"
$PN"1"21;
%"RES"
"1","(-6900,4350)","0","mstr_discrete","I67";
;
PART_NUMBER"G21796-066"
PACK_TYPE"0402"
LOCATION"R1L25"
TOLERANCE"1%"
VALUE"10.0"
WATTAGE"1/16W"
BOM_COST"DEBUG"
ROOM"BMC_DEBUG_HEADER"
CDS_LIB"mstr_discrete"
CDS_LOCATION"R1L25"
MATERIAL"CHIP"
CDS_SEC"1"
$SEC"1";
"B"
$PN"2"27;
"A"
$PN"1"19;
%"RES"
"1","(-6900,4200)","0","mstr_discrete","I68";
;
PART_NUMBER"G21796-066"
PACK_TYPE"0402"
TOLERANCE"1%"
LOCATION"R1L24"
VALUE"10.0"
WATTAGE"1/16W"
CDS_LIB"mstr_discrete"
CDS_SEC"1"
$SEC"1"
BOM_COST"DEBUG"
ROOM"BMC_DEBUG_HEADER"
CDS_LOCATION"R1L24"
MATERIAL"CHIP";
"B"
$PN"2"28;
"A"
$PN"1"20;
%"RES"
"1","(-6900,4050)","0","mstr_discrete","I73";
;
LOCATION"R1L20"
PART_NUMBER"G21796-066"
PACK_TYPE"0402"
TOLERANCE"1%"
VALUE"10.0"
WATTAGE"1/16W"
BOM_COST"DEBUG"
CDS_SEC"1"
$SEC"1"
ROOM"BMC_DEBUG_HEADER"
CDS_LOCATION"R1L20"
CDS_LIB"mstr_discrete"
MATERIAL"CHIP";
"B"
$PN"2"24;
"A"
$PN"1"18;
%"RES"
"1","(-6900,3900)","0","mstr_discrete","I74";
;
PART_NUMBER"G21796-066"
PACK_TYPE"0402"
TOLERANCE"1%"
LOCATION"R1L18"
VALUE"10.0"
WATTAGE"1/16W"
CDS_SEC"1"
$SEC"1"
CDS_LIB"mstr_discrete"
MATERIAL"CHIP"
BOM_COST"DEBUG"
ROOM"BMC_DEBUG_HEADER"
CDS_LOCATION"R1L18";
"B"
$PN"2"25;
"A"
$PN"1"17;
%"RES"
"1","(-6900,3750)","0","mstr_discrete","I75";
;
PART_NUMBER"G21796-066"
PACK_TYPE"0402"
TOLERANCE"1%"
LOCATION"R1L14"
VALUE"10.0"
WATTAGE"1/16W"
CDS_LIB"mstr_discrete"
MATERIAL"CHIP"
BOM_COST"DEBUG"
CDS_SEC"1"
$SEC"1"
ROOM"BMC_DEBUG_HEADER"
CDS_LOCATION"R1L14";
"B"
$PN"2"45;
"A"
$PN"1"16;
%"RES"
"1","(-6900,3600)","0","mstr_discrete","I76";
;
PART_NUMBER"G21796-066"
TOLERANCE"1%"
LOCATION"R1L11"
VALUE"10.0"
WATTAGE"1/16W"
PACK_TYPE"0402"
CDS_LIB"mstr_discrete"
MATERIAL"CHIP"
ROOM"BMC_DEBUG_HEADER"
CDS_LOCATION"R1L11"
$SEC"1"
CDS_SEC"1"
BOM_COST"DEBUG";
"B"
$PN"2"23;
"A"
$PN"1"15;
%"RES"
"2","(-1900,1725)","0","mstr_discrete","I80";
;
ROOM"BMC_DEBUG_HEADER"
CDS_LOCATION"R9A7"
SEC"1"
BOM_COST"DEBUG"
SEC_TYPE"0402"
CDS_LIB"mstr_discrete"
WATTAGE"1/16W"
PART_NUMBER"G21796-112"
TOLERANCE"1%"
MATERIAL"CHIP"
LOCATION"R9A7"
VALUE"2.21K"
PACK_TYPE"0402"
CDS_SEC"1";
"A"
$PN"1"1;
"B"
$PN"2"46;
%"P3V3_STBY"
"1","(-1900,1975)","0","mstr_symbols","I81";
;
SIZE"1B"
BODY_TYPE"PLUMBING"
CDS_LIB"mstr_symbols"
VOLTAGE"3.3V"
HDL_POWER"P3V3_STBY";
"G\NAC"1;
END.
